(kicad_pcb
	(version 20260206)
	(generator "pcbnew")
	(generator_version "10.0")
	(general
		(thickness 1.6)
		(legacy_teardrops no)
	)
	(paper "A4")
	(title_block
		(title "03242023_DA0F0TMBIJ0_F0T_Motherboard_J_brd_V01_OCP.brd")
		(comment 1 "Grand Teton / footprint 1585 of 6105 (U4), pads 1-113 of 749")
	)
	(layers
		(0 "F.Cu" signal "TOP")
		(4 "In1.Cu" signal "GND")
		(6 "In2.Cu" signal "IN1")
		(8 "In3.Cu" signal "GND1")
		(10 "In4.Cu" signal "IN2")
		(12 "In5.Cu" signal "GND2")
		(14 "In6.Cu" signal "IN3")
		(16 "In7.Cu" signal "GND3")
		(18 "In8.Cu" signal "VCC")
		(20 "In9.Cu" signal "VCC1")
		(22 "In10.Cu" signal "GND4")
		(24 "In11.Cu" signal "IN4")
		(26 "In12.Cu" signal "GND5")
		(28 "In13.Cu" signal "IN5")
		(30 "In14.Cu" signal "GND6")
		(32 "In15.Cu" signal "IN6")
		(34 "In16.Cu" signal "GND7")
		(2 "B.Cu" signal "BOTTOM")
		(9 "F.Adhes" user "F.Adhesive")
		(11 "B.Adhes" user "B.Adhesive")
		(13 "F.Paste" user "Package Geometry/Pastemask Top")
		(15 "B.Paste" user "Package Geometry/Pastemask Bottom")
		(5 "F.SilkS" user "Ref Des/Silkscreen Top")
		(7 "B.SilkS" user "Ref Des/Silkscreen Bottom")
		(1 "F.Mask" user "Board Geometry/Soldermask Top")
		(3 "B.Mask" user "Board Geometry/Soldermask Bottom")
		(17 "Dwgs.User" user "User.Drawings")
		(19 "Cmts.User" user "User.Comments")
		(21 "Eco1.User" user "User.Eco1")
		(23 "Eco2.User" user "User.Eco2")
		(25 "Edge.Cuts" user "Board Geometry/Outline")
		(27 "Margin" user)
		(31 "F.CrtYd" user "Package Geometry/Place Bound Top")
		(29 "B.CrtYd" user "Package Geometry/Place Bound Bottom")
		(35 "F.Fab" user "Ref Des/Assembly Top")
		(33 "B.Fab" user "Ref Des/Assembly Bottom")
	)
	(footprint ""
		(layer "F.Cu")
		(at 336.899758 -48.450246)
		(property "Reference" "U4"
			(at -13.479018 -11.486896 0)
			(unlocked yes)
			(layer "F.SilkS")
			(effects
				(font
					(size 0.7874 0.5842)
					(thickness 0.1524)
				)
				(justify left)
			)
		)
		(property "Value" ""
			(at 0 0 0)
			(layer "F.Fab")
			(effects
				(font
					(size 1.27 1.27)
				)
			)
		)
		(duplicate_pad_numbers_are_jumpers no)
		(pad "A4" smd circle
			(at -9.0043 -10.815066 180)
			(size 0.4064 0.4064)
			(layers "F.Cu" "F.Mask" "F.Paste")
			(net "TP_PCH_RSVD<2>")
		)
		(pad "A6" smd circle
			(at -8.003794 -10.815066 180)
			(size 0.4064 0.4064)
			(layers "F.Cu" "F.Mask" "F.Paste")
			(net "GND")
		)
		(pad "A8" smd oval
			(at -7.003288 -10.815066 180)
			(size 0.254 0.3302)
			(layers "F.Cu" "F.Mask" "F.Paste")
			(net "TP_CLK_100M_PCH_13_DN")
		)
		(pad "A10" smd oval
			(at -6.002782 -10.815066 180)
			(size 0.254 0.3302)
			(layers "F.Cu" "F.Mask" "F.Paste")
			(net "TP_CLK_100M_PCH_12_DN")
		)
		(pad "A12" smd oval
			(at -5.002276 -10.815066 180)
			(size 0.254 0.3302)
			(layers "F.Cu" "F.Mask" "F.Paste")
			(net "TP_CLK_100M_PCH_5_DN")
		)
		(pad "A14" smd oval
			(at -4.002024 -10.815066 180)
			(size 0.254 0.3302)
			(layers "F.Cu" "F.Mask" "F.Paste")
			(net "TP_CLK_100M_PCH_7_DN")
		)
		(pad "A16" smd oval
			(at -3.001518 -10.815066 180)
			(size 0.254 0.3302)
			(layers "F.Cu" "F.Mask" "F.Paste")
			(net "TP_CLK_100M_PCH_0_DN")
		)
		(pad "A18" smd oval
			(at -2.001012 -10.815066 180)
			(size 0.254 0.3302)
			(layers "F.Cu" "F.Mask" "F.Paste")
			(net "TP_CLK_100M_PCH_16_DN")
		)
		(pad "A20" smd oval
			(at -1.000506 -10.815066 180)
			(size 0.254 0.3302)
			(layers "F.Cu" "F.Mask" "F.Paste")
			(net "GND")
		)
		(pad "A22" smd oval
			(at 0 -10.815066 180)
			(size 0.254 0.3302)
			(layers "F.Cu" "F.Mask" "F.Paste")
			(net "GND")
		)
		(pad "A24" smd oval
			(at 1.000506 -10.815066 180)
			(size 0.254 0.3302)
			(layers "F.Cu" "F.Mask" "F.Paste")
			(net "GND")
		)
		(pad "A26" smd oval
			(at 2.001012 -10.815066 180)
			(size 0.254 0.3302)
			(layers "F.Cu" "F.Mask" "F.Paste")
			(net "GND")
		)
		(pad "A28" smd oval
			(at 3.001518 -10.815066 180)
			(size 0.254 0.3302)
			(layers "F.Cu" "F.Mask" "F.Paste")
			(net "CLK_25M_PCH_CPU1_DP")
		)
		(pad "A30" smd oval
			(at 4.002024 -10.815066 180)
			(size 0.254 0.3302)
			(layers "F.Cu" "F.Mask" "F.Paste")
			(net "DMI_CPU0_PCH_TX_C_DN<0>")
		)
		(pad "A32" smd oval
			(at 5.002276 -10.815066 180)
			(size 0.254 0.3302)
			(layers "F.Cu" "F.Mask" "F.Paste")
			(net "DMI_CPU0_PCH_TX_C_DN<2>")
		)
		(pad "A34" smd oval
			(at 6.002782 -10.815066 180)
			(size 0.254 0.3302)
			(layers "F.Cu" "F.Mask" "F.Paste")
			(net "DMI_CPU0_PCH_TX_C_DN<4>")
		)
		(pad "A36" smd oval
			(at 7.003288 -10.815066 180)
			(size 0.254 0.3302)
			(layers "F.Cu" "F.Mask" "F.Paste")
			(net "DMI_CPU0_PCH_TX_C_DN<6>")
		)
		(pad "A38" smd circle
			(at 8.003794 -10.815066 180)
			(size 0.4064 0.4064)
			(layers "F.Cu" "F.Mask" "F.Paste")
			(net "GND")
		)
		(pad "A40" smd circle
			(at 9.0043 -10.815066 180)
			(size 0.4064 0.4064)
			(layers "F.Cu" "F.Mask" "F.Paste")
			(net "GND")
		)
		(pad "A41" smd circle
			(at 9.65962 -10.815066 180)
			(size 0.4064 0.4064)
			(layers "F.Cu" "F.Mask" "F.Paste")
			(net "FM_PCH_PRSNT_N")
		)
		(pad "AA1" smd oval
			(at -10.31494 -1.500632 270)
			(size 0.254 0.3302)
			(layers "F.Cu" "F.Mask" "F.Paste")
			(net "FM_PCH_GLB_RST_WARN_N")
		)
		(pad "AA3" smd circle
			(at -9.484868 -1.500632 180)
			(size 0.3048 0.3048)
			(layers "F.Cu" "F.Mask" "F.Paste")
			(net "FM_BIOS_DEBUG_EN_R_N")
		)
		(pad "AA5" smd circle
			(at -8.654796 -1.500632 180)
			(size 0.3048 0.3048)
			(layers "F.Cu" "F.Mask" "F.Paste")
			(net "GND")
		)
		(pad "AA7" smd circle
			(at -7.733792 -1.4097 180)
			(size 0.381 0.381)
			(layers "F.Cu" "F.Mask" "F.Paste")
			(net "FAB_REV_ID2")
		)
		(pad "AA10" smd circle
			(at -6.105398 -1.4097 180)
			(size 0.381 0.381)
			(layers "F.Cu" "F.Mask" "F.Paste")
			(net "FM_BOARD_SKU_ID0")
		)
		(pad "AA13" smd circle
			(at -4.477512 -1.4097 180)
			(size 0.381 0.381)
			(layers "F.Cu" "F.Mask" "F.Paste")
			(net "FAB_REV_ID1")
		)
		(pad "AA17" smd circle
			(at -2.4003 -1.6002 180)
			(size 0.381 0.381)
			(layers "F.Cu" "F.Mask" "F.Paste")
			(net "GND")
		)
		(pad "AA19" smd circle
			(at -1.6002 -1.6002 180)
			(size 0.381 0.381)
			(layers "F.Cu" "F.Mask" "F.Paste")
			(net "GND")
		)
		(pad "AA20" smd circle
			(at -0.8001 -1.6002 180)
			(size 0.381 0.381)
			(layers "F.Cu" "F.Mask" "F.Paste")
			(net "GND")
		)
		(pad "AA22" smd circle
			(at 0 -1.6002 180)
			(size 0.381 0.381)
			(layers "F.Cu" "F.Mask" "F.Paste")
			(net "GND")
		)
		(pad "AA24" smd circle
			(at 0.8001 -1.6002 180)
			(size 0.381 0.381)
			(layers "F.Cu" "F.Mask" "F.Paste")
			(net "GND")
		)
		(pad "AA25" smd circle
			(at 1.6002 -1.6002 180)
			(size 0.381 0.381)
			(layers "F.Cu" "F.Mask" "F.Paste")
			(net "GND")
		)
		(pad "AA27" smd circle
			(at 2.4003 -1.6002 180)
			(size 0.381 0.381)
			(layers "F.Cu" "F.Mask" "F.Paste")
			(net "GND")
		)
		(pad "AA29" smd circle
			(at 3.663188 -1.4097 180)
			(size 0.381 0.381)
			(layers "F.Cu" "F.Mask" "F.Paste")
			(net "P1V05_PCH_PLL_AUX")
		)
		(pad "AA32" smd circle
			(at 5.291582 -1.4097 180)
			(size 0.381 0.381)
			(layers "F.Cu" "F.Mask" "F.Paste")
			(net "GND")
		)
		(pad "AA36" smd circle
			(at 6.919722 -1.4097 180)
			(size 0.381 0.381)
			(layers "F.Cu" "F.Mask" "F.Paste")
			(net "GND")
		)
		(pad "AA39" smd circle
			(at 8.654796 -1.500632 180)
			(size 0.3048 0.3048)
			(layers "F.Cu" "F.Mask" "F.Paste")
			(net "GND")
		)
		(pad "AA41" smd circle
			(at 9.484868 -1.500632 180)
			(size 0.3048 0.3048)
			(layers "F.Cu" "F.Mask" "F.Paste")
			(net "P3E_PCH_E1S_RX_DN<0>")
		)
		(pad "AA43" smd oval
			(at 10.31494 -1.500632 270)
			(size 0.254 0.3302)
			(layers "F.Cu" "F.Mask" "F.Paste")
			(net "P3E_PCH_E1S_RX_DP<0>")
		)
		(pad "AB2" smd circle
			(at -9.899904 -1.000506 180)
			(size 0.3048 0.3048)
			(layers "F.Cu" "F.Mask" "F.Paste")
			(net "IRQ_PCH_SCI_WHEA_N")
		)
		(pad "AB4" smd circle
			(at -9.069832 -1.000506 180)
			(size 0.3048 0.3048)
			(layers "F.Cu" "F.Mask" "F.Paste")
			(net "RST_PLTRST_N")
		)
		(pad "AB8" smd circle
			(at -6.919722 -0.9398 180)
			(size 0.381 0.381)
			(layers "F.Cu" "F.Mask" "F.Paste")
			(net "FM_PASSWORD_CLEAR_N")
		)
		(pad "AB11" smd circle
			(at -5.291582 -0.9398 180)
			(size 0.381 0.381)
			(layers "F.Cu" "F.Mask" "F.Paste")
			(net "FM_BOARD_SKU_ID4")
		)
		(pad "AB15" smd circle
			(at -3.663188 -0.9398 180)
			(size 0.381 0.381)
			(layers "F.Cu" "F.Mask" "F.Paste")
			(net "GND")
		)
		(pad "AB17" smd circle
			(at -2.4003 -0.8001 180)
			(size 0.381 0.381)
			(layers "F.Cu" "F.Mask" "F.Paste")
			(net "GND")
		)
		(pad "AB19" smd circle
			(at -1.6002 -0.8001 180)
			(size 0.381 0.381)
			(layers "F.Cu" "F.Mask" "F.Paste")
			(net "P1V05_PCH_AUX")
		)
		(pad "AB20" smd circle
			(at -0.8001 -0.8001 180)
			(size 0.381 0.381)
			(layers "F.Cu" "F.Mask" "F.Paste")
			(net "P1V05_PCH_AUX")
		)
		(pad "AB22" smd circle
			(at 0 -0.8001 180)
			(size 0.381 0.381)
			(layers "F.Cu" "F.Mask" "F.Paste")
			(net "P1V05_PCH_AUX")
		)
		(pad "AB24" smd circle
			(at 0.8001 -0.8001 180)
			(size 0.381 0.381)
			(layers "F.Cu" "F.Mask" "F.Paste")
			(net "P1V05_PCH_AUX")
		)
		(pad "AB25" smd circle
			(at 1.6002 -0.8001 180)
			(size 0.381 0.381)
			(layers "F.Cu" "F.Mask" "F.Paste")
			(net "GND")
		)
		(pad "AB27" smd circle
			(at 2.4003 -0.8001 180)
			(size 0.381 0.381)
			(layers "F.Cu" "F.Mask" "F.Paste")
			(net "P1V05_PCH_PLL_AUX")
		)
		(pad "AB31" smd circle
			(at 4.477512 -0.9398 180)
			(size 0.381 0.381)
			(layers "F.Cu" "F.Mask" "F.Paste")
			(net "P1V8_PCH_PLL_AUX")
		)
		(pad "AB34" smd circle
			(at 6.105398 -0.9398 180)
			(size 0.381 0.381)
			(layers "F.Cu" "F.Mask" "F.Paste")
			(net "P1V8_PCH_PLL_AUX")
		)
		(pad "AB37" smd circle
			(at 7.733792 -0.9398 180)
			(size 0.381 0.381)
			(layers "F.Cu" "F.Mask" "F.Paste")
			(net "GND")
		)
		(pad "AB40" smd circle
			(at 9.069832 -1.000506 180)
			(size 0.3048 0.3048)
			(layers "F.Cu" "F.Mask" "F.Paste")
			(net "P3E_PCH_M2_RX_DN<3>")
		)
		(pad "AB42" smd circle
			(at 9.899904 -1.000506 180)
			(size 0.3048 0.3048)
			(layers "F.Cu" "F.Mask" "F.Paste")
			(net "P3E_PCH_M2_RX_DP<3>")
		)
		(pad "AC1" smd oval
			(at -10.31494 -0.500126 270)
			(size 0.254 0.3302)
			(layers "F.Cu" "F.Mask" "F.Paste")
			(net "FM_ADR_COMPLETE")
		)
		(pad "AC3" smd circle
			(at -9.484868 -0.500126 180)
			(size 0.3048 0.3048)
			(layers "F.Cu" "F.Mask" "F.Paste")
			(net "PU_PCH_VRALERT_N")
		)
		(pad "AC5" smd circle
			(at -8.654796 -0.500126 180)
			(size 0.3048 0.3048)
			(layers "F.Cu" "F.Mask" "F.Paste")
			(net "GND")
		)
		(pad "AC7" smd circle
			(at -7.733792 -0.4699 180)
			(size 0.381 0.381)
			(layers "F.Cu" "F.Mask" "F.Paste")
			(net "TP_GPP_L_7")
		)
		(pad "AC10" smd circle
			(at -6.105398 -0.4699 180)
			(size 0.381 0.381)
			(layers "F.Cu" "F.Mask" "F.Paste")
			(net "TP_GPP_L_2")
		)
		(pad "AC13" smd circle
			(at -4.477512 -0.4699 180)
			(size 0.381 0.381)
			(layers "F.Cu" "F.Mask" "F.Paste")
			(net "PD_RCOMP_1P8_3P3")
		)
		(pad "AC29" smd circle
			(at 3.663188 -0.4699 180)
			(size 0.381 0.381)
			(layers "F.Cu" "F.Mask" "F.Paste")
			(net "GND")
		)
		(pad "AC32" smd circle
			(at 5.291582 -0.4699 180)
			(size 0.381 0.381)
			(layers "F.Cu" "F.Mask" "F.Paste")
			(net "GND")
		)
		(pad "AC36" smd circle
			(at 6.919722 -0.4699 180)
			(size 0.381 0.381)
			(layers "F.Cu" "F.Mask" "F.Paste")
			(net "GND")
		)
		(pad "AC39" smd circle
			(at 8.654796 -0.500126 180)
			(size 0.3048 0.3048)
			(layers "F.Cu" "F.Mask" "F.Paste")
			(net "GND")
		)
		(pad "AC41" smd circle
			(at 9.484868 -0.500126 180)
			(size 0.3048 0.3048)
			(layers "F.Cu" "F.Mask" "F.Paste")
			(net "P3E_PCH_M2_RX_DN<2>")
		)
		(pad "AC43" smd oval
			(at 10.31494 -0.500126 270)
			(size 0.254 0.3302)
			(layers "F.Cu" "F.Mask" "F.Paste")
			(net "P3E_PCH_M2_RX_DP<2>")
		)
		(pad "AD2" smd circle
			(at -9.899904 0 180)
			(size 0.3048 0.3048)
			(layers "F.Cu" "F.Mask" "F.Paste")
			(net "TP_PCH_GPP_D_2")
		)
		(pad "AD4" smd circle
			(at -9.069832 0 180)
			(size 0.3048 0.3048)
			(layers "F.Cu" "F.Mask" "F.Paste")
			(net "FM_ADR_ACK")
		)
		(pad "AD8" smd circle
			(at -6.919722 0 180)
			(size 0.381 0.381)
			(layers "F.Cu" "F.Mask" "F.Paste")
			(net "GND")
		)
		(pad "AD11" smd circle
			(at -5.291582 0 180)
			(size 0.381 0.381)
			(layers "F.Cu" "F.Mask" "F.Paste")
			(net "GND")
		)
		(pad "AD15" smd circle
			(at -3.663188 0 180)
			(size 0.381 0.381)
			(layers "F.Cu" "F.Mask" "F.Paste")
			(net "P3V3_AUX")
		)
		(pad "AD17" smd circle
			(at -2.4003 0 180)
			(size 0.381 0.381)
			(layers "F.Cu" "F.Mask" "F.Paste")
			(net "P3V3_AUX")
		)
		(pad "AD19" smd circle
			(at -1.6002 0 180)
			(size 0.381 0.381)
			(layers "F.Cu" "F.Mask" "F.Paste")
			(net "GND")
		)
		(pad "AD20" smd circle
			(at -0.8001 0 180)
			(size 0.381 0.381)
			(layers "F.Cu" "F.Mask" "F.Paste")
			(net "GND")
		)
		(pad "AD22" smd circle
			(at 0 0 180)
			(size 0.381 0.381)
			(layers "F.Cu" "F.Mask" "F.Paste")
			(net "GND")
		)
		(pad "AD24" smd circle
			(at 0.8001 0 180)
			(size 0.381 0.381)
			(layers "F.Cu" "F.Mask" "F.Paste")
			(net "GND")
		)
		(pad "AD25" smd circle
			(at 1.6002 0 180)
			(size 0.381 0.381)
			(layers "F.Cu" "F.Mask" "F.Paste")
			(net "P1V05_PCH_AUX")
		)
		(pad "AD27" smd circle
			(at 2.4003 0 180)
			(size 0.381 0.381)
			(layers "F.Cu" "F.Mask" "F.Paste")
			(net "P1V05_PCH_AUX")
		)
		(pad "AD31" smd circle
			(at 4.477512 0 180)
			(size 0.381 0.381)
			(layers "F.Cu" "F.Mask" "F.Paste")
			(net "GND")
		)
		(pad "AD34" smd circle
			(at 6.105398 0 180)
			(size 0.381 0.381)
			(layers "F.Cu" "F.Mask" "F.Paste")
			(net "GND")
		)
		(pad "AD37" smd circle
			(at 7.733792 0 180)
			(size 0.381 0.381)
			(layers "F.Cu" "F.Mask" "F.Paste")
			(net "P3E_PCH_BMC_TX_DP")
		)
		(pad "AD40" smd circle
			(at 9.069832 0 180)
			(size 0.3048 0.3048)
			(layers "F.Cu" "F.Mask" "F.Paste")
			(net "P3E_PCH_M2_RX_DN<1>")
		)
		(pad "AD42" smd circle
			(at 9.899904 0 180)
			(size 0.3048 0.3048)
			(layers "F.Cu" "F.Mask" "F.Paste")
			(net "P3E_PCH_M2_RX_DP<1>")
		)
		(pad "AE1" smd oval
			(at -10.31494 0.500126 270)
			(size 0.254 0.3302)
			(layers "F.Cu" "F.Mask" "F.Paste")
			(net "SMB_HOST_BMC_3V3AUX_SDA")
		)
		(pad "AE3" smd circle
			(at -9.484868 0.500126 180)
			(size 0.3048 0.3048)
			(layers "F.Cu" "F.Mask" "F.Paste")
			(net "FM_PCH_CRASHLOG_TRIG_N")
		)
		(pad "AE5" smd circle
			(at -8.654796 0.500126 180)
			(size 0.3048 0.3048)
			(layers "F.Cu" "F.Mask" "F.Paste")
			(net "GND")
		)
		(pad "AE7" smd circle
			(at -7.733792 0.4699 180)
			(size 0.381 0.381)
			(layers "F.Cu" "F.Mask" "F.Paste")
			(net "H_CPU0_PMDOWN_PCH")
		)
		(pad "AE10" smd circle
			(at -6.105398 0.4699 180)
			(size 0.381 0.381)
			(layers "F.Cu" "F.Mask" "F.Paste")
			(net "TP_GPP_L_8")
		)
		(pad "AE13" smd circle
			(at -4.477512 0.4699 180)
			(size 0.381 0.381)
			(layers "F.Cu" "F.Mask" "F.Paste")
			(net "GND")
		)
		(pad "AE29" smd circle
			(at 3.663188 0.4699 180)
			(size 0.381 0.381)
			(layers "F.Cu" "F.Mask" "F.Paste")
			(net "P1V05_PCH_PLL_AUX")
		)
		(pad "AE32" smd circle
			(at 5.291582 0.4699 180)
			(size 0.381 0.381)
			(layers "F.Cu" "F.Mask" "F.Paste")
			(net "USB3_PCH_TX_DN<4>")
		)
		(pad "AE36" smd circle
			(at 6.919722 0.4699 180)
			(size 0.381 0.381)
			(layers "F.Cu" "F.Mask" "F.Paste")
			(net "P3E_PCH_BMC_TX_DN")
		)
		(pad "AE39" smd circle
			(at 8.654796 0.500126 180)
			(size 0.3048 0.3048)
			(layers "F.Cu" "F.Mask" "F.Paste")
			(net "GND")
		)
		(pad "AE41" smd circle
			(at 9.484868 0.500126 180)
			(size 0.3048 0.3048)
			(layers "F.Cu" "F.Mask" "F.Paste")
			(net "P3E_PCH_M2_RX_DN<0>")
		)
		(pad "AE43" smd oval
			(at 10.31494 0.500126 270)
			(size 0.254 0.3302)
			(layers "F.Cu" "F.Mask" "F.Paste")
			(net "P3E_PCH_M2_RX_DP<0>")
		)
		(pad "AF2" smd circle
			(at -9.899904 1.000506 180)
			(size 0.3048 0.3048)
			(layers "F.Cu" "F.Mask" "F.Paste")
			(net "SMB_HOST_BMC_3V3AUX_SCL")
		)
		(pad "AF4" smd circle
			(at -9.069832 1.000506 180)
			(size 0.3048 0.3048)
			(layers "F.Cu" "F.Mask" "F.Paste")
			(net "FM_CPU_RMCA_CATERR_DLY_N")
		)
		(pad "AF8" smd circle
			(at -6.919722 0.9398 180)
			(size 0.381 0.381)
			(layers "F.Cu" "F.Mask" "F.Paste")
			(net "H_CPU0_PMSYNC_PCH_R2")
		)
		(pad "AF11" smd circle
			(at -5.291582 0.9398 180)
			(size 0.381 0.381)
			(layers "F.Cu" "F.Mask" "F.Paste")
			(net "FM_BIOS_ADV_FUNCTIONS")
		)
		(pad "AF15" smd circle
			(at -3.663188 0.9398 180)
			(size 0.381 0.381)
			(layers "F.Cu" "F.Mask" "F.Paste")
			(net "TP_PCH_RSVD<16>")
		)
		(pad "AF17" smd circle
			(at -2.4003 0.8001 180)
			(size 0.381 0.381)
			(layers "F.Cu" "F.Mask" "F.Paste")
			(net "P3V3_AUX")
		)
		(pad "AF19" smd circle
			(at -1.6002 0.8001 180)
			(size 0.381 0.381)
			(layers "F.Cu" "F.Mask" "F.Paste")
			(net "GND")
		)
		(pad "AF20" smd circle
			(at -0.8001 0.8001 180)
			(size 0.381 0.381)
			(layers "F.Cu" "F.Mask" "F.Paste")
			(net "P1V05_PCH_AUX")
		)
		(pad "AF22" smd circle
			(at 0 0.8001 180)
			(size 0.381 0.381)
			(layers "F.Cu" "F.Mask" "F.Paste")
			(net "P1V05_PCH_AUX")
		)
		(pad "AF24" smd circle
			(at 0.8001 0.8001 180)
			(size 0.381 0.381)
			(layers "F.Cu" "F.Mask" "F.Paste")
			(net "GND")
		)
		(pad "AF25" smd circle
			(at 1.6002 0.8001 180)
			(size 0.381 0.381)
			(layers "F.Cu" "F.Mask" "F.Paste")
			(net "P1V05_PCH_AUX")
		)
		(pad "AF27" smd circle
			(at 2.4003 0.8001 180)
			(size 0.381 0.381)
			(layers "F.Cu" "F.Mask" "F.Paste")
			(net "P1V05_PCH_AUX")
		)
		(pad "AF31" smd circle
			(at 4.477512 0.9398 180)
			(size 0.381 0.381)
			(layers "F.Cu" "F.Mask" "F.Paste")
			(net "GND")
		)
		(pad "AF34" smd circle
			(at 6.105398 0.9398 180)
			(size 0.381 0.381)
			(layers "F.Cu" "F.Mask" "F.Paste")
			(net "P3E_PCH_E1S_TX_DN<3>")
		)
		(pad "AF37" smd circle
			(at 7.733792 0.9398 180)
			(size 0.381 0.381)
			(layers "F.Cu" "F.Mask" "F.Paste")
			(net "P3E_PCH_E1S_TX_DN<2>")
		)
		(pad "AF40" smd circle
			(at 9.069832 1.000506 180)
			(size 0.3048 0.3048)
			(layers "F.Cu" "F.Mask" "F.Paste")
			(net "GND")
		)
	)
)
